/usr/tools/22/concept_lib/dwg_sym/gnd/logic.1.1: \
	/usr/tools/22/concept_lib/standard/drawing/body.1.1\
	/usr/tools/22/concept_lib/standard/synonym/body.1.1
	/u0/editor/MakeAddToList "</usr/tools/22/concept_lib/dwg_sym/dwg_sym.lib>GND.LOGIC.1.1"
